(kicad_pcb
	(version 20260206)
	(generator "pcbnew")
	(generator_version "10.0")
	(general
		(thickness 1.6)
		(legacy_teardrops no)
	)
	(paper "A4")
	(title_block
		(title "03242023_DA0F0TMBIJ0_F0T_Motherboard_J_brd_V01_OCP.brd")
		(comment 1 "Grand Teton / footprints 99-104 of 6105")
	)
	(layers
		(0 "F.Cu" signal "TOP")
		(4 "In1.Cu" signal "GND")
		(6 "In2.Cu" signal "IN1")
		(8 "In3.Cu" signal "GND1")
		(10 "In4.Cu" signal "IN2")
		(12 "In5.Cu" signal "GND2")
		(14 "In6.Cu" signal "IN3")
		(16 "In7.Cu" signal "GND3")
		(18 "In8.Cu" signal "VCC")
		(20 "In9.Cu" signal "VCC1")
		(22 "In10.Cu" signal "GND4")
		(24 "In11.Cu" signal "IN4")
		(26 "In12.Cu" signal "GND5")
		(28 "In13.Cu" signal "IN5")
		(30 "In14.Cu" signal "GND6")
		(32 "In15.Cu" signal "IN6")
		(34 "In16.Cu" signal "GND7")
		(2 "B.Cu" signal "BOTTOM")
		(9 "F.Adhes" user "F.Adhesive")
		(11 "B.Adhes" user "B.Adhesive")
		(13 "F.Paste" user "Package Geometry/Pastemask Top")
		(15 "B.Paste" user "Package Geometry/Pastemask Bottom")
		(5 "F.SilkS" user "Ref Des/Silkscreen Top")
		(7 "B.SilkS" user "Ref Des/Silkscreen Bottom")
		(1 "F.Mask" user "Board Geometry/Soldermask Top")
		(3 "B.Mask" user "Board Geometry/Soldermask Bottom")
		(17 "Dwgs.User" user "User.Drawings")
		(19 "Cmts.User" user "User.Comments")
		(21 "Eco1.User" user "User.Eco1")
		(23 "Eco2.User" user "User.Eco2")
		(25 "Edge.Cuts" user "Board Geometry/Outline")
		(27 "Margin" user)
		(31 "F.CrtYd" user "Package Geometry/Place Bound Top")
		(29 "B.CrtYd" user "Package Geometry/Place Bound Bottom")
		(35 "F.Fab" user "Ref Des/Assembly Top")
		(33 "B.Fab" user "Ref Des/Assembly Bottom")
	)
	(footprint ""
		(layer "F.Cu")
		(at 106.322114 -260.36524 -90)
		(property "Reference" "C435"
			(at 0 0 270)
			(layer "F.SilkS")
			(hide yes)
			(effects
				(font
					(size 1.27 1.27)
				)
			)
		)
		(property "Value" ""
			(at 0 0 270)
			(layer "F.Fab")
			(effects
				(font
					(size 1.27 1.27)
				)
			)
		)
		(duplicate_pad_numbers_are_jumpers no)
		(fp_line
			(start -0.7874 0.4064)
			(end -0.7874 -0.4064)
			(stroke
				(width 0.1524)
				(type default)
			)
			(layer "F.SilkS")
		)
		(fp_line
			(start 0.7874 0.4064)
			(end -0.7874 0.4064)
			(stroke
				(width 0.1524)
				(type default)
			)
			(layer "F.SilkS")
		)
		(fp_line
			(start -0.7874 -0.4064)
			(end 0.7874 -0.4064)
			(stroke
				(width 0.1524)
				(type default)
			)
			(layer "F.SilkS")
		)
		(fp_line
			(start 0.7874 -0.4064)
			(end 0.7874 0.4064)
			(stroke
				(width 0.1524)
				(type default)
			)
			(layer "F.SilkS")
		)
		(fp_line
			(start -0.67945 0.3048)
			(end -0.67945 -0.305054)
			(stroke
				(width 0.1)
				(type default)
			)
			(layer "F.Fab")
		)
		(fp_line
			(start -0.12065 0.3048)
			(end -0.67945 0.3048)
			(stroke
				(width 0.1)
				(type default)
			)
			(layer "F.Fab")
		)
		(fp_line
			(start 0.120396 0.3048)
			(end 0.120396 0.2794)
			(stroke
				(width 0.1)
				(type default)
			)
			(layer "F.Fab")
		)
		(fp_line
			(start 0.67945 0.3048)
			(end 0.120396 0.3048)
			(stroke
				(width 0.1)
				(type default)
			)
			(layer "F.Fab")
		)
		(fp_line
			(start -0.12065 0.2794)
			(end -0.12065 0.3048)
			(stroke
				(width 0.1)
				(type default)
			)
			(layer "F.Fab")
		)
		(fp_line
			(start 0.120396 0.2794)
			(end -0.12065 0.2794)
			(stroke
				(width 0.1)
				(type default)
			)
			(layer "F.Fab")
		)
		(fp_line
			(start -0.12065 -0.2794)
			(end 0.12065 -0.2794)
			(stroke
				(width 0.1)
				(type default)
			)
			(layer "F.Fab")
		)
		(fp_line
			(start 0.12065 -0.2794)
			(end 0.12065 -0.3048)
			(stroke
				(width 0.1)
				(type default)
			)
			(layer "F.Fab")
		)
		(fp_line
			(start 0.12065 -0.3048)
			(end 0.67945 -0.3048)
			(stroke
				(width 0.1)
				(type default)
			)
			(layer "F.Fab")
		)
		(fp_line
			(start 0.67945 -0.3048)
			(end 0.67945 0.3048)
			(stroke
				(width 0.1)
				(type default)
			)
			(layer "F.Fab")
		)
		(fp_line
			(start -0.67945 -0.305054)
			(end -0.12065 -0.305054)
			(stroke
				(width 0.1)
				(type default)
			)
			(layer "F.Fab")
		)
		(fp_line
			(start -0.12065 -0.305054)
			(end -0.12065 -0.2794)
			(stroke
				(width 0.1)
				(type default)
			)
			(layer "F.Fab")
		)
		(pad "1" smd circle
			(at -0.40005 0 270)
			(size 0 0)
			(layers "F.Cu" "F.Mask" "F.Paste")
			(net "PVCCFA_EHV_FIVRA_CPU1")
		)
		(pad "2" smd circle
			(at 0.40005 0 270)
			(size 0 0)
			(layers "F.Cu" "F.Mask" "F.Paste")
			(net "GND")
		)
	)
	(footprint ""
		(layer "F.Cu")
		(at 132.51688 -100.167948 -90)
		(property "Reference" "R202"
			(at 0 0 270)
			(layer "F.SilkS")
			(hide yes)
			(effects
				(font
					(size 1.27 1.27)
				)
			)
		)
		(property "Value" ""
			(at 0 0 270)
			(layer "F.Fab")
			(effects
				(font
					(size 1.27 1.27)
				)
			)
		)
		(duplicate_pad_numbers_are_jumpers no)
		(fp_line
			(start -0.7874 0.4064)
			(end -0.7874 -0.4064)
			(stroke
				(width 0.1524)
				(type default)
			)
			(layer "F.SilkS")
		)
		(fp_line
			(start 0.7874 0.4064)
			(end -0.7874 0.4064)
			(stroke
				(width 0.1524)
				(type default)
			)
			(layer "F.SilkS")
		)
		(fp_line
			(start -0.7874 -0.4064)
			(end 0.7874 -0.4064)
			(stroke
				(width 0.1524)
				(type default)
			)
			(layer "F.SilkS")
		)
		(fp_line
			(start 0.7874 -0.4064)
			(end 0.7874 0.4064)
			(stroke
				(width 0.1524)
				(type default)
			)
			(layer "F.SilkS")
		)
		(fp_line
			(start -0.67945 0.3048)
			(end -0.67945 -0.305054)
			(stroke
				(width 0.1)
				(type default)
			)
			(layer "F.Fab")
		)
		(fp_line
			(start -0.12065 0.3048)
			(end -0.67945 0.3048)
			(stroke
				(width 0.1)
				(type default)
			)
			(layer "F.Fab")
		)
		(fp_line
			(start 0.120396 0.3048)
			(end 0.120396 0.2794)
			(stroke
				(width 0.1)
				(type default)
			)
			(layer "F.Fab")
		)
		(fp_line
			(start 0.67945 0.3048)
			(end 0.120396 0.3048)
			(stroke
				(width 0.1)
				(type default)
			)
			(layer "F.Fab")
		)
		(fp_line
			(start -0.12065 0.2794)
			(end -0.12065 0.3048)
			(stroke
				(width 0.1)
				(type default)
			)
			(layer "F.Fab")
		)
		(fp_line
			(start 0.120396 0.2794)
			(end -0.12065 0.2794)
			(stroke
				(width 0.1)
				(type default)
			)
			(layer "F.Fab")
		)
		(fp_line
			(start -0.12065 -0.2794)
			(end 0.12065 -0.2794)
			(stroke
				(width 0.1)
				(type default)
			)
			(layer "F.Fab")
		)
		(fp_line
			(start 0.12065 -0.2794)
			(end 0.12065 -0.3048)
			(stroke
				(width 0.1)
				(type default)
			)
			(layer "F.Fab")
		)
		(fp_line
			(start 0.12065 -0.3048)
			(end 0.67945 -0.3048)
			(stroke
				(width 0.1)
				(type default)
			)
			(layer "F.Fab")
		)
		(fp_line
			(start 0.67945 -0.3048)
			(end 0.67945 0.3048)
			(stroke
				(width 0.1)
				(type default)
			)
			(layer "F.Fab")
		)
		(fp_line
			(start -0.67945 -0.305054)
			(end -0.12065 -0.305054)
			(stroke
				(width 0.1)
				(type default)
			)
			(layer "F.Fab")
		)
		(fp_line
			(start -0.12065 -0.305054)
			(end -0.12065 -0.2794)
			(stroke
				(width 0.1)
				(type default)
			)
			(layer "F.Fab")
		)
		(pad "1" smd circle
			(at -0.40005 0 270)
			(size 0 0)
			(layers "F.Cu" "F.Mask" "F.Paste")
			(net "PVNN_TERM_CPU1")
		)
		(pad "2" smd circle
			(at 0.40005 0 270)
			(size 0 0)
			(layers "F.Cu" "F.Mask" "F.Paste")
			(net "H_CPU1_MEMTRIP_LVC1_R_N")
		)
	)
	(footprint ""
		(layer "F.Cu")
		(at 13.546582 -423.629836 -90)
		(property "Reference" "R2982"
			(at 0 0 270)
			(layer "F.SilkS")
			(hide yes)
			(effects
				(font
					(size 1.27 1.27)
				)
			)
		)
		(property "Value" ""
			(at 0 0 270)
			(layer "F.Fab")
			(effects
				(font
					(size 1.27 1.27)
				)
			)
		)
		(duplicate_pad_numbers_are_jumpers no)
		(fp_line
			(start -0.7874 0.4064)
			(end -0.7874 -0.4064)
			(stroke
				(width 0.1524)
				(type default)
			)
			(layer "F.SilkS")
		)
		(fp_line
			(start 0.7874 0.4064)
			(end -0.7874 0.4064)
			(stroke
				(width 0.1524)
				(type default)
			)
			(layer "F.SilkS")
		)
		(fp_line
			(start -0.7874 -0.4064)
			(end 0.7874 -0.4064)
			(stroke
				(width 0.1524)
				(type default)
			)
			(layer "F.SilkS")
		)
		(fp_line
			(start 0.7874 -0.4064)
			(end 0.7874 0.4064)
			(stroke
				(width 0.1524)
				(type default)
			)
			(layer "F.SilkS")
		)
		(fp_line
			(start -0.67945 0.3048)
			(end -0.67945 -0.305054)
			(stroke
				(width 0.1)
				(type default)
			)
			(layer "F.Fab")
		)
		(fp_line
			(start -0.12065 0.3048)
			(end -0.67945 0.3048)
			(stroke
				(width 0.1)
				(type default)
			)
			(layer "F.Fab")
		)
		(fp_line
			(start 0.120396 0.3048)
			(end 0.120396 0.2794)
			(stroke
				(width 0.1)
				(type default)
			)
			(layer "F.Fab")
		)
		(fp_line
			(start 0.67945 0.3048)
			(end 0.120396 0.3048)
			(stroke
				(width 0.1)
				(type default)
			)
			(layer "F.Fab")
		)
		(fp_line
			(start -0.12065 0.2794)
			(end -0.12065 0.3048)
			(stroke
				(width 0.1)
				(type default)
			)
			(layer "F.Fab")
		)
		(fp_line
			(start 0.120396 0.2794)
			(end -0.12065 0.2794)
			(stroke
				(width 0.1)
				(type default)
			)
			(layer "F.Fab")
		)
		(fp_line
			(start -0.12065 -0.2794)
			(end 0.12065 -0.2794)
			(stroke
				(width 0.1)
				(type default)
			)
			(layer "F.Fab")
		)
		(fp_line
			(start 0.12065 -0.2794)
			(end 0.12065 -0.3048)
			(stroke
				(width 0.1)
				(type default)
			)
			(layer "F.Fab")
		)
		(fp_line
			(start 0.12065 -0.3048)
			(end 0.67945 -0.3048)
			(stroke
				(width 0.1)
				(type default)
			)
			(layer "F.Fab")
		)
		(fp_line
			(start 0.67945 -0.3048)
			(end 0.67945 0.3048)
			(stroke
				(width 0.1)
				(type default)
			)
			(layer "F.Fab")
		)
		(fp_line
			(start -0.67945 -0.305054)
			(end -0.12065 -0.305054)
			(stroke
				(width 0.1)
				(type default)
			)
			(layer "F.Fab")
		)
		(fp_line
			(start -0.12065 -0.305054)
			(end -0.12065 -0.2794)
			(stroke
				(width 0.1)
				(type default)
			)
			(layer "F.Fab")
		)
		(pad "1" smd circle
			(at -0.40005 0 270)
			(size 0 0)
			(layers "F.Cu" "F.Mask" "F.Paste")
			(net "SMB_IOEXP_3V3AUX_SCL")
		)
		(pad "2" smd circle
			(at 0.40005 0 270)
			(size 0 0)
			(layers "F.Cu" "F.Mask" "F.Paste")
			(net "SMB_IOEXP_3V3AUX_SCL_R1")
		)
	)
	(footprint ""
		(layer "F.Cu")
		(at 9.58088 -59.019948)
		(property "Reference" "R3059"
			(at 0 0 0)
			(layer "F.SilkS")
			(hide yes)
			(effects
				(font
					(size 1.27 1.27)
				)
			)
		)
		(property "Value" ""
			(at 0 0 0)
			(layer "F.Fab")
			(effects
				(font
					(size 1.27 1.27)
				)
			)
		)
		(duplicate_pad_numbers_are_jumpers no)
		(fp_line
			(start -0.7874 -0.4064)
			(end 0.7874 -0.4064)
			(stroke
				(width 0.1524)
				(type default)
			)
			(layer "F.SilkS")
		)
		(fp_line
			(start -0.7874 0.4064)
			(end -0.7874 -0.4064)
			(stroke
				(width 0.1524)
				(type default)
			)
			(layer "F.SilkS")
		)
		(fp_line
			(start 0.7874 -0.4064)
			(end 0.7874 0.4064)
			(stroke
				(width 0.1524)
				(type default)
			)
			(layer "F.SilkS")
		)
		(fp_line
			(start 0.7874 0.4064)
			(end -0.7874 0.4064)
			(stroke
				(width 0.1524)
				(type default)
			)
			(layer "F.SilkS")
		)
		(fp_line
			(start -0.67945 -0.305054)
			(end -0.12065 -0.305054)
			(stroke
				(width 0.1)
				(type default)
			)
			(layer "F.Fab")
		)
		(fp_line
			(start -0.67945 0.3048)
			(end -0.67945 -0.305054)
			(stroke
				(width 0.1)
				(type default)
			)
			(layer "F.Fab")
		)
		(fp_line
			(start -0.12065 -0.305054)
			(end -0.12065 -0.2794)
			(stroke
				(width 0.1)
				(type default)
			)
			(layer "F.Fab")
		)
		(fp_line
			(start -0.12065 -0.2794)
			(end 0.12065 -0.2794)
			(stroke
				(width 0.1)
				(type default)
			)
			(layer "F.Fab")
		)
		(fp_line
			(start -0.12065 0.2794)
			(end -0.12065 0.3048)
			(stroke
				(width 0.1)
				(type default)
			)
			(layer "F.Fab")
		)
		(fp_line
			(start -0.12065 0.3048)
			(end -0.67945 0.3048)
			(stroke
				(width 0.1)
				(type default)
			)
			(layer "F.Fab")
		)
		(fp_line
			(start 0.120396 0.2794)
			(end -0.12065 0.2794)
			(stroke
				(width 0.1)
				(type default)
			)
			(layer "F.Fab")
		)
		(fp_line
			(start 0.120396 0.3048)
			(end 0.120396 0.2794)
			(stroke
				(width 0.1)
				(type default)
			)
			(layer "F.Fab")
		)
		(fp_line
			(start 0.12065 -0.3048)
			(end 0.67945 -0.3048)
			(stroke
				(width 0.1)
				(type default)
			)
			(layer "F.Fab")
		)
		(fp_line
			(start 0.12065 -0.2794)
			(end 0.12065 -0.3048)
			(stroke
				(width 0.1)
				(type default)
			)
			(layer "F.Fab")
		)
		(fp_line
			(start 0.67945 -0.3048)
			(end 0.67945 0.3048)
			(stroke
				(width 0.1)
				(type default)
			)
			(layer "F.Fab")
		)
		(fp_line
			(start 0.67945 0.3048)
			(end 0.120396 0.3048)
			(stroke
				(width 0.1)
				(type default)
			)
			(layer "F.Fab")
		)
		(pad "1" smd circle
			(at -0.40005 0)
			(size 0 0)
			(layers "F.Cu" "F.Mask" "F.Paste")
			(net "SMB_SML0_3V3AUX_SDA")
		)
		(pad "2" smd circle
			(at 0.40005 0)
			(size 0 0)
			(layers "F.Cu" "F.Mask" "F.Paste")
			(net "SMB_SML0_ME_SDA")
		)
	)
	(footprint ""
		(layer "F.Cu")
		(at 421.038528 -140.186156 -90)
		(property "Reference" "PR121"
			(at 0 0 270)
			(layer "F.SilkS")
			(hide yes)
			(effects
				(font
					(size 1.27 1.27)
				)
			)
		)
		(property "Value" ""
			(at 0 0 270)
			(layer "F.Fab")
			(effects
				(font
					(size 1.27 1.27)
				)
			)
		)
		(duplicate_pad_numbers_are_jumpers no)
		(fp_line
			(start -0.7874 0.4064)
			(end -0.7874 -0.4064)
			(stroke
				(width 0.1524)
				(type default)
			)
			(layer "F.SilkS")
		)
		(fp_line
			(start 0.7874 0.4064)
			(end -0.7874 0.4064)
			(stroke
				(width 0.1524)
				(type default)
			)
			(layer "F.SilkS")
		)
		(fp_line
			(start -0.7874 -0.4064)
			(end 0.7874 -0.4064)
			(stroke
				(width 0.1524)
				(type default)
			)
			(layer "F.SilkS")
		)
		(fp_line
			(start 0.7874 -0.4064)
			(end 0.7874 0.4064)
			(stroke
				(width 0.1524)
				(type default)
			)
			(layer "F.SilkS")
		)
		(fp_line
			(start -0.67945 0.3048)
			(end -0.67945 -0.305054)
			(stroke
				(width 0.1)
				(type default)
			)
			(layer "F.Fab")
		)
		(fp_line
			(start -0.12065 0.3048)
			(end -0.67945 0.3048)
			(stroke
				(width 0.1)
				(type default)
			)
			(layer "F.Fab")
		)
		(fp_line
			(start 0.120396 0.3048)
			(end 0.120396 0.2794)
			(stroke
				(width 0.1)
				(type default)
			)
			(layer "F.Fab")
		)
		(fp_line
			(start 0.67945 0.3048)
			(end 0.120396 0.3048)
			(stroke
				(width 0.1)
				(type default)
			)
			(layer "F.Fab")
		)
		(fp_line
			(start -0.12065 0.2794)
			(end -0.12065 0.3048)
			(stroke
				(width 0.1)
				(type default)
			)
			(layer "F.Fab")
		)
		(fp_line
			(start 0.120396 0.2794)
			(end -0.12065 0.2794)
			(stroke
				(width 0.1)
				(type default)
			)
			(layer "F.Fab")
		)
		(fp_line
			(start -0.12065 -0.2794)
			(end 0.12065 -0.2794)
			(stroke
				(width 0.1)
				(type default)
			)
			(layer "F.Fab")
		)
		(fp_line
			(start 0.12065 -0.2794)
			(end 0.12065 -0.3048)
			(stroke
				(width 0.1)
				(type default)
			)
			(layer "F.Fab")
		)
		(fp_line
			(start 0.12065 -0.3048)
			(end 0.67945 -0.3048)
			(stroke
				(width 0.1)
				(type default)
			)
			(layer "F.Fab")
		)
		(fp_line
			(start 0.67945 -0.3048)
			(end 0.67945 0.3048)
			(stroke
				(width 0.1)
				(type default)
			)
			(layer "F.Fab")
		)
		(fp_line
			(start -0.67945 -0.305054)
			(end -0.12065 -0.305054)
			(stroke
				(width 0.1)
				(type default)
			)
			(layer "F.Fab")
		)
		(fp_line
			(start -0.12065 -0.305054)
			(end -0.12065 -0.2794)
			(stroke
				(width 0.1)
				(type default)
			)
			(layer "F.Fab")
		)
		(pad "1" smd circle
			(at -0.40005 0 270)
			(size 0 0)
			(layers "F.Cu" "F.Mask" "F.Paste")
			(net "SH_PVCCFA_EHV_CPU0")
		)
		(pad "2" smd circle
			(at 0.40005 0 270)
			(size 0 0)
			(layers "F.Cu" "F.Mask" "F.Paste")
			(net "SH_PVCCFA_EHV_CPU0_R")
		)
	)
	(footprint ""
		(layer "F.Cu")
		(at 367.44783 -258.726686 90)
		(property "Reference" "C980"
			(at 0 0 90)
			(layer "F.SilkS")
			(hide yes)
			(effects
				(font
					(size 1.27 1.27)
				)
			)
		)
		(property "Value" ""
			(at 0 0 90)
			(layer "F.Fab")
			(effects
				(font
					(size 1.27 1.27)
				)
			)
		)
		(duplicate_pad_numbers_are_jumpers no)
		(fp_line
			(start 0.7874 -0.4064)
			(end 0.7874 0.4064)
			(stroke
				(width 0.1524)
				(type default)
			)
			(layer "F.SilkS")
		)
		(fp_line
			(start -0.7874 -0.4064)
			(end 0.7874 -0.4064)
			(stroke
				(width 0.1524)
				(type default)
			)
			(layer "F.SilkS")
		)
		(fp_line
			(start 0.7874 0.4064)
			(end -0.7874 0.4064)
			(stroke
				(width 0.1524)
				(type default)
			)
			(layer "F.SilkS")
		)
		(fp_line
			(start -0.7874 0.4064)
			(end -0.7874 -0.4064)
			(stroke
				(width 0.1524)
				(type default)
			)
			(layer "F.SilkS")
		)
		(fp_line
			(start -0.12065 -0.305054)
			(end -0.12065 -0.2794)
			(stroke
				(width 0.1)
				(type default)
			)
			(layer "F.Fab")
		)
		(fp_line
			(start -0.67945 -0.305054)
			(end -0.12065 -0.305054)
			(stroke
				(width 0.1)
				(type default)
			)
			(layer "F.Fab")
		)
		(fp_line
			(start 0.67945 -0.3048)
			(end 0.67945 0.3048)
			(stroke
				(width 0.1)
				(type default)
			)
			(layer "F.Fab")
		)
		(fp_line
			(start 0.12065 -0.3048)
			(end 0.67945 -0.3048)
			(stroke
				(width 0.1)
				(type default)
			)
			(layer "F.Fab")
		)
		(fp_line
			(start 0.12065 -0.2794)
			(end 0.12065 -0.3048)
			(stroke
				(width 0.1)
				(type default)
			)
			(layer "F.Fab")
		)
		(fp_line
			(start -0.12065 -0.2794)
			(end 0.12065 -0.2794)
			(stroke
				(width 0.1)
				(type default)
			)
			(layer "F.Fab")
		)
		(fp_line
			(start 0.120396 0.2794)
			(end -0.12065 0.2794)
			(stroke
				(width 0.1)
				(type default)
			)
			(layer "F.Fab")
		)
		(fp_line
			(start -0.12065 0.2794)
			(end -0.12065 0.3048)
			(stroke
				(width 0.1)
				(type default)
			)
			(layer "F.Fab")
		)
		(fp_line
			(start 0.67945 0.3048)
			(end 0.120396 0.3048)
			(stroke
				(width 0.1)
				(type default)
			)
			(layer "F.Fab")
		)
		(fp_line
			(start 0.120396 0.3048)
			(end 0.120396 0.2794)
			(stroke
				(width 0.1)
				(type default)
			)
			(layer "F.Fab")
		)
		(fp_line
			(start -0.12065 0.3048)
			(end -0.67945 0.3048)
			(stroke
				(width 0.1)
				(type default)
			)
			(layer "F.Fab")
		)
		(fp_line
			(start -0.67945 0.3048)
			(end -0.67945 -0.305054)
			(stroke
				(width 0.1)
				(type default)
			)
			(layer "F.Fab")
		)
		(pad "1" smd circle
			(at -0.40005 0 90)
			(size 0 0)
			(layers "F.Cu" "F.Mask" "F.Paste")
			(net "PVCCIN_CPU0")
		)
		(pad "2" smd circle
			(at 0.40005 0 90)
			(size 0 0)
			(layers "F.Cu" "F.Mask" "F.Paste")
			(net "GND")
		)
	)
)
